(kicad_pcb
	(version 20260206)
	(generator "pcbnew")
	(generator_version "10.0")
	(general
		(thickness 1.6)
		(legacy_teardrops no)
	)
	(paper "A4")
	(title_block
		(title "v1-chassis-manager — T6M_CM_d_v01_1031_1645.brd")
		(comment 1 "Open CloudServer (Microsoft) / footprints 1641-1649 of 2512")
	)
	(layers
		(0 "F.Cu" signal "TOP")
		(4 "In1.Cu" signal "GND1")
		(6 "In2.Cu" signal "IN1")
		(8 "In3.Cu" signal "VCC1")
		(10 "In4.Cu" signal "VCC2")
		(12 "In5.Cu" signal "GND2")
		(14 "In6.Cu" signal "IN2")
		(16 "In7.Cu" signal "IN3")
		(18 "In8.Cu" signal "GND3")
		(2 "B.Cu" signal "BOTTOM")
		(9 "F.Adhes" user "F.Adhesive")
		(11 "B.Adhes" user "B.Adhesive")
		(13 "F.Paste" user "Package Geometry/Pastemask Top")
		(15 "B.Paste" user "Package Geometry/Pastemask Bottom")
		(5 "F.SilkS" user "Ref Des/Silkscreen Top")
		(7 "B.SilkS" user "Ref Des/Silkscreen Bottom")
		(1 "F.Mask" user "Board Geometry/Soldermask Top")
		(3 "B.Mask" user "Board Geometry/Soldermask Bottom")
		(17 "Dwgs.User" user "User.Drawings")
		(19 "Cmts.User" user "User.Comments")
		(21 "Eco1.User" user "User.Eco1")
		(23 "Eco2.User" user "User.Eco2")
		(25 "Edge.Cuts" user "Board Geometry/Outline")
		(27 "Margin" user)
		(31 "F.CrtYd" user "Package Geometry/Place Bound Top")
		(29 "B.CrtYd" user "Package Geometry/Place Bound Bottom")
		(35 "F.Fab" user "Ref Des/Assembly Top")
		(33 "B.Fab" user "Ref Des/Assembly Bottom")
	)
	(footprint ""
		(layer "B.Cu")
		(at 39.120572 -68.957698 180)
		(property "Reference" "C16"
			(at -3.139948 0.106172 0)
			(unlocked yes)
			(layer "B.SilkS")
			(effects
				(font
					(size 0.7874 0.5842)
					(thickness 0.1524)
				)
				(justify left mirror)
			)
		)
		(property "Value" ""
			(at 0 0 0)
			(layer "B.Fab")
			(effects
				(font
					(size 1.27 1.27)
				)
				(justify mirror)
			)
		)
		(duplicate_pad_numbers_are_jumpers no)
		(fp_line
			(start 0.7874 0.4064)
			(end 0.7874 -0.4064)
			(stroke
				(width 0.1524)
				(type default)
			)
			(layer "B.SilkS")
		)
		(fp_line
			(start 0.7874 -0.4064)
			(end -0.7874 -0.4064)
			(stroke
				(width 0.1524)
				(type default)
			)
			(layer "B.SilkS")
		)
		(fp_line
			(start 0 0.381)
			(end 0 -0.381)
			(stroke
				(width 0.1524)
				(type default)
			)
			(layer "B.SilkS")
		)
		(fp_line
			(start -0.7874 0.4064)
			(end 0.7874 0.4064)
			(stroke
				(width 0.1524)
				(type default)
			)
			(layer "B.SilkS")
		)
		(fp_line
			(start -0.7874 -0.4064)
			(end -0.7874 0.4064)
			(stroke
				(width 0.1524)
				(type default)
			)
			(layer "B.SilkS")
		)
		(fp_poly
			(pts
				(xy 0.5334 0.254) (xy 0.635 0.254) (xy 0.635 0.2286) (xy 0.635 -0.254) (xy 0.5334 -0.254) (xy 0.5334 -0.2794)
				(xy -0.5334 -0.2794) (xy -0.5334 -0.254) (xy -0.635 -0.254) (xy -0.635 0.254) (xy -0.5334 0.254)
				(xy -0.5334 0.2794) (xy 0.508 0.2794) (xy 0.5334 0.2794)
			)
			(stroke
				(width 0)
				(type default)
			)
			(fill no)
			(layer "B.CrtYd")
		)
		(pad "1" smd rect
			(at -0.40005 0)
			(size 0.4572 0.508)
			(layers "B.Cu" "B.Mask" "B.Paste")
			(net "P2E_CPU_PCIE_SW_NODE1_TX_C_DN")
		)
		(pad "2" smd rect
			(at 0.40005 0)
			(size 0.4572 0.508)
			(layers "B.Cu" "B.Mask" "B.Paste")
			(net "P2E_CPU_PCIE_SW_NODE1_TX_DN")
		)
	)
	(footprint ""
		(layer "B.Cu")
		(at 35.713162 -104.82707 90)
		(property "Reference" "C821"
			(at 0.935736 1.886712 270)
			(unlocked yes)
			(layer "B.SilkS")
			(effects
				(font
					(size 0.7874 0.5842)
					(thickness 0.1524)
				)
				(justify left mirror)
			)
		)
		(property "Value" ""
			(at 0 0 90)
			(layer "B.Fab")
			(effects
				(font
					(size 1.27 1.27)
				)
				(justify mirror)
			)
		)
		(duplicate_pad_numbers_are_jumpers no)
		(fp_line
			(start 1.905 -0.8636)
			(end -1.905 -0.8636)
			(stroke
				(width 0.1524)
				(type default)
			)
			(layer "B.SilkS")
		)
		(fp_line
			(start -1.905 -0.8636)
			(end -1.905 0.8636)
			(stroke
				(width 0.1524)
				(type default)
			)
			(layer "B.SilkS")
		)
		(fp_line
			(start 0 0.8382)
			(end 0 -0.8382)
			(stroke
				(width 0.1524)
				(type default)
			)
			(layer "B.SilkS")
		)
		(fp_line
			(start 1.905 0.8636)
			(end 1.905 -0.8636)
			(stroke
				(width 0.1524)
				(type default)
			)
			(layer "B.SilkS")
		)
		(fp_line
			(start -1.905 0.8636)
			(end 1.905 0.8636)
			(stroke
				(width 0.1524)
				(type default)
			)
			(layer "B.SilkS")
		)
		(fp_rect
			(start 1.524 0.7366)
			(end -1.524 -0.7366)
			(stroke
				(width 0)
				(type default)
			)
			(fill no)
			(layer "B.CrtYd")
		)
		(pad "1" smd rect
			(at -0.94996 0 270)
			(size 1.1176 1.3716)
			(layers "B.Cu" "B.Mask" "B.Paste")
			(net "P1V5_SUS_NODE1")
		)
		(pad "2" smd rect
			(at 0.94996 0 270)
			(size 1.1176 1.3716)
			(layers "B.Cu" "B.Mask" "B.Paste")
			(net "GND")
		)
	)
	(footprint ""
		(layer "B.Cu")
		(at 78.21676 -188.126624 -90)
		(property "Reference" "C649"
			(at -4.151884 0.365252 270)
			(unlocked yes)
			(layer "B.SilkS")
			(effects
				(font
					(size 0.7874 0.5842)
					(thickness 0.1524)
				)
				(justify left mirror)
			)
		)
		(property "Value" ""
			(at 0 0 90)
			(layer "B.Fab")
			(effects
				(font
					(size 1.27 1.27)
				)
				(justify mirror)
			)
		)
		(duplicate_pad_numbers_are_jumpers no)
		(fp_line
			(start -0.7874 0.4064)
			(end 0.7874 0.4064)
			(stroke
				(width 0.1524)
				(type default)
			)
			(layer "B.SilkS")
		)
		(fp_line
			(start 0.7874 0.4064)
			(end 0.7874 -0.4064)
			(stroke
				(width 0.1524)
				(type default)
			)
			(layer "B.SilkS")
		)
		(fp_line
			(start 0 0.381)
			(end 0 -0.381)
			(stroke
				(width 0.1524)
				(type default)
			)
			(layer "B.SilkS")
		)
		(fp_line
			(start -0.7874 -0.4064)
			(end -0.7874 0.4064)
			(stroke
				(width 0.1524)
				(type default)
			)
			(layer "B.SilkS")
		)
		(fp_line
			(start 0.7874 -0.4064)
			(end -0.7874 -0.4064)
			(stroke
				(width 0.1524)
				(type default)
			)
			(layer "B.SilkS")
		)
		(fp_poly
			(pts
				(xy 0.5334 0.254) (xy 0.635 0.254) (xy 0.635 0.2286) (xy 0.635 -0.254) (xy 0.5334 -0.254) (xy 0.5334 -0.2794)
				(xy -0.5334 -0.2794) (xy -0.5334 -0.254) (xy -0.635 -0.254) (xy -0.635 0.254) (xy -0.5334 0.254)
				(xy -0.5334 0.2794) (xy 0.508 0.2794) (xy 0.5334 0.2794)
			)
			(stroke
				(width 0)
				(type default)
			)
			(fill no)
			(layer "B.CrtYd")
		)
		(pad "1" smd rect
			(at -0.40005 0 90)
			(size 0.4572 0.508)
			(layers "B.Cu" "B.Mask" "B.Paste")
			(net "T3_NODE2_EN_R")
		)
		(pad "2" smd rect
			(at 0.40005 0 90)
			(size 0.4572 0.508)
			(layers "B.Cu" "B.Mask" "B.Paste")
			(net "GND")
		)
	)
	(footprint ""
		(layer "B.Cu")
		(at 68.379086 -118.758462 -90)
		(property "Reference" "R329"
			(at 5.085334 0.574548 270)
			(unlocked yes)
			(layer "B.SilkS")
			(effects
				(font
					(size 0.7874 0.5842)
					(thickness 0.1524)
				)
				(justify left mirror)
			)
		)
		(property "Value" ""
			(at 0 0 90)
			(layer "B.Fab")
			(effects
				(font
					(size 1.27 1.27)
				)
				(justify mirror)
			)
		)
		(duplicate_pad_numbers_are_jumpers no)
		(fp_line
			(start -0.7874 0.4064)
			(end 0.7874 0.4064)
			(stroke
				(width 0.1524)
				(type default)
			)
			(layer "B.SilkS")
		)
		(fp_line
			(start 0.7874 0.4064)
			(end 0.7874 -0.4064)
			(stroke
				(width 0.1524)
				(type default)
			)
			(layer "B.SilkS")
		)
		(fp_line
			(start -0.7874 -0.4064)
			(end -0.7874 0.4064)
			(stroke
				(width 0.1524)
				(type default)
			)
			(layer "B.SilkS")
		)
		(fp_line
			(start 0.7874 -0.4064)
			(end -0.7874 -0.4064)
			(stroke
				(width 0.1524)
				(type default)
			)
			(layer "B.SilkS")
		)
		(fp_poly
			(pts
				(xy 0.508 0.2794) (xy 0.508 0.2286) (xy 0.635 0.2286) (xy 0.635 -0.254) (xy 0.5334 -0.254) (xy 0.5334 -0.2794)
				(xy -0.5334 -0.2794) (xy -0.5334 -0.254) (xy -0.635 -0.254) (xy -0.635 0.254) (xy -0.5334 0.254)
				(xy -0.5334 0.2794)
			)
			(stroke
				(width 0)
				(type default)
			)
			(fill no)
			(layer "B.CrtYd")
		)
		(pad "1" smd rect
			(at -0.40005 0 90)
			(size 0.4572 0.508)
			(layers "B.Cu" "B.Mask" "B.Paste")
			(net "P3V3_NODE1")
		)
		(pad "2" smd rect
			(at 0.40005 0 90)
			(size 0.4572 0.508)
			(layers "B.Cu" "B.Mask" "B.Paste")
			(net "BMC_ROMA13")
		)
	)
	(footprint ""
		(layer "B.Cu")
		(at 147.305014 -70.635622 180)
		(property "Reference" "C350"
			(at -4.93522 0.558038 0)
			(unlocked yes)
			(layer "B.SilkS")
			(effects
				(font
					(size 0.7874 0.5842)
					(thickness 0.1524)
				)
				(justify left mirror)
			)
		)
		(property "Value" ""
			(at 0 0 0)
			(layer "B.Fab")
			(effects
				(font
					(size 1.27 1.27)
				)
				(justify mirror)
			)
		)
		(duplicate_pad_numbers_are_jumpers no)
		(fp_line
			(start 0.7874 0.4064)
			(end 0.7874 -0.4064)
			(stroke
				(width 0.1524)
				(type default)
			)
			(layer "B.SilkS")
		)
		(fp_line
			(start 0.7874 -0.4064)
			(end -0.7874 -0.4064)
			(stroke
				(width 0.1524)
				(type default)
			)
			(layer "B.SilkS")
		)
		(fp_line
			(start 0 0.381)
			(end 0 -0.381)
			(stroke
				(width 0.1524)
				(type default)
			)
			(layer "B.SilkS")
		)
		(fp_line
			(start -0.7874 0.4064)
			(end 0.7874 0.4064)
			(stroke
				(width 0.1524)
				(type default)
			)
			(layer "B.SilkS")
		)
		(fp_line
			(start -0.7874 -0.4064)
			(end -0.7874 0.4064)
			(stroke
				(width 0.1524)
				(type default)
			)
			(layer "B.SilkS")
		)
		(fp_poly
			(pts
				(xy 0.5334 0.254) (xy 0.635 0.254) (xy 0.635 0.2286) (xy 0.635 -0.254) (xy 0.5334 -0.254) (xy 0.5334 -0.2794)
				(xy -0.5334 -0.2794) (xy -0.5334 -0.254) (xy -0.635 -0.254) (xy -0.635 0.254) (xy -0.5334 0.254)
				(xy -0.5334 0.2794) (xy 0.508 0.2794) (xy 0.5334 0.2794)
			)
			(stroke
				(width 0)
				(type default)
			)
			(fill no)
			(layer "B.CrtYd")
		)
		(pad "1" smd rect
			(at -0.40005 0)
			(size 0.4572 0.508)
			(layers "B.Cu" "B.Mask" "B.Paste")
			(net "P1V8_SATA_AVDD_NODE1")
		)
		(pad "2" smd rect
			(at 0.40005 0)
			(size 0.4572 0.508)
			(layers "B.Cu" "B.Mask" "B.Paste")
			(net "GND")
		)
	)
	(footprint ""
		(layer "B.Cu")
		(at 142.07236 -177.077624 180)
		(property "Reference" "R736"
			(at 1.250188 1.24079 0)
			(unlocked yes)
			(layer "B.SilkS")
			(effects
				(font
					(size 0.7874 0.5842)
					(thickness 0.1524)
				)
				(justify left mirror)
			)
		)
		(property "Value" ""
			(at 0 0 0)
			(layer "B.Fab")
			(effects
				(font
					(size 1.27 1.27)
				)
				(justify mirror)
			)
		)
		(duplicate_pad_numbers_are_jumpers no)
		(fp_line
			(start 0.7874 0.4064)
			(end 0.7874 -0.4064)
			(stroke
				(width 0.1524)
				(type default)
			)
			(layer "B.SilkS")
		)
		(fp_line
			(start 0.7874 -0.4064)
			(end -0.7874 -0.4064)
			(stroke
				(width 0.1524)
				(type default)
			)
			(layer "B.SilkS")
		)
		(fp_line
			(start -0.7874 0.4064)
			(end 0.7874 0.4064)
			(stroke
				(width 0.1524)
				(type default)
			)
			(layer "B.SilkS")
		)
		(fp_line
			(start -0.7874 -0.4064)
			(end -0.7874 0.4064)
			(stroke
				(width 0.1524)
				(type default)
			)
			(layer "B.SilkS")
		)
		(fp_poly
			(pts
				(xy 0.508 0.2794) (xy 0.508 0.2286) (xy 0.635 0.2286) (xy 0.635 -0.254) (xy 0.5334 -0.254) (xy 0.5334 -0.2794)
				(xy -0.5334 -0.2794) (xy -0.5334 -0.254) (xy -0.635 -0.254) (xy -0.635 0.254) (xy -0.5334 0.254)
				(xy -0.5334 0.2794)
			)
			(stroke
				(width 0)
				(type default)
			)
			(fill no)
			(layer "B.CrtYd")
		)
		(pad "1" smd rect
			(at -0.40005 0)
			(size 0.4572 0.508)
			(layers "B.Cu" "B.Mask" "B.Paste")
			(net "T10_NODE3_EN")
		)
		(pad "2" smd rect
			(at 0.40005 0)
			(size 0.4572 0.508)
			(layers "B.Cu" "B.Mask" "B.Paste")
			(net "P5V_NODE1")
		)
	)
	(footprint ""
		(layer "B.Cu")
		(at 180.660294 -159.333692 -90)
		(property "Reference" "C520"
			(at -2.62382 -0.065024 270)
			(unlocked yes)
			(layer "B.SilkS")
			(effects
				(font
					(size 0.7874 0.5842)
					(thickness 0.1524)
				)
				(justify left mirror)
			)
		)
		(property "Value" ""
			(at 0 0 90)
			(layer "B.Fab")
			(effects
				(font
					(size 1.27 1.27)
				)
				(justify mirror)
			)
		)
		(duplicate_pad_numbers_are_jumpers no)
		(fp_line
			(start -0.7874 0.4064)
			(end 0.7874 0.4064)
			(stroke
				(width 0.1524)
				(type default)
			)
			(layer "B.SilkS")
		)
		(fp_line
			(start 0.7874 0.4064)
			(end 0.7874 -0.4064)
			(stroke
				(width 0.1524)
				(type default)
			)
			(layer "B.SilkS")
		)
		(fp_line
			(start 0 0.381)
			(end 0 -0.381)
			(stroke
				(width 0.1524)
				(type default)
			)
			(layer "B.SilkS")
		)
		(fp_line
			(start -0.7874 -0.4064)
			(end -0.7874 0.4064)
			(stroke
				(width 0.1524)
				(type default)
			)
			(layer "B.SilkS")
		)
		(fp_line
			(start 0.7874 -0.4064)
			(end -0.7874 -0.4064)
			(stroke
				(width 0.1524)
				(type default)
			)
			(layer "B.SilkS")
		)
		(fp_poly
			(pts
				(xy 0.5334 0.254) (xy 0.635 0.254) (xy 0.635 0.2286) (xy 0.635 -0.254) (xy 0.5334 -0.254) (xy 0.5334 -0.2794)
				(xy -0.5334 -0.2794) (xy -0.5334 -0.254) (xy -0.635 -0.254) (xy -0.635 0.254) (xy -0.5334 0.254)
				(xy -0.5334 0.2794) (xy 0.508 0.2794) (xy 0.5334 0.2794)
			)
			(stroke
				(width 0)
				(type default)
			)
			(fill no)
			(layer "B.CrtYd")
		)
		(pad "1" smd rect
			(at -0.40005 0 90)
			(size 0.4572 0.508)
			(layers "B.Cu" "B.Mask" "B.Paste")
			(net "P1V9_LAN2")
		)
		(pad "2" smd rect
			(at 0.40005 0 90)
			(size 0.4572 0.508)
			(layers "B.Cu" "B.Mask" "B.Paste")
			(net "GND")
		)
	)
	(footprint ""
		(layer "B.Cu")
		(at 100.44176 -176.569624 -90)
		(property "Reference" "U65"
			(at 0.310388 5.50291 270)
			(unlocked yes)
			(layer "B.SilkS")
			(effects
				(font
					(size 0.7874 0.5842)
					(thickness 0.1524)
				)
				(justify left mirror)
			)
		)
		(property "Value" ""
			(at 0 0 90)
			(layer "B.Fab")
			(effects
				(font
					(size 1.27 1.27)
				)
				(justify mirror)
			)
		)
		(duplicate_pad_numbers_are_jumpers no)
		(fp_line
			(start -3.9624 2.0066)
			(end 3.9624 2.0066)
			(stroke
				(width 0.1524)
				(type default)
			)
			(layer "B.SilkS")
		)
		(fp_line
			(start 3.9624 2.0066)
			(end 3.9624 0.5842)
			(stroke
				(width 0.1524)
				(type default)
			)
			(layer "B.SilkS")
		)
		(fp_line
			(start 3.9624 0.5842)
			(end 3.3782 0)
			(stroke
				(width 0.1524)
				(type default)
			)
			(layer "B.SilkS")
		)
		(fp_line
			(start 3.3782 0)
			(end 3.9624 -0.5842)
			(stroke
				(width 0.1524)
				(type default)
			)
			(layer "B.SilkS")
		)
		(fp_line
			(start 3.9624 -0.5842)
			(end 3.9624 -2.0066)
			(stroke
				(width 0.1524)
				(type default)
			)
			(layer "B.SilkS")
		)
		(fp_line
			(start -3.9624 -2.0066)
			(end -3.9624 2.0066)
			(stroke
				(width 0.1524)
				(type default)
			)
			(layer "B.SilkS")
		)
		(fp_line
			(start 3.9624 -2.0066)
			(end -3.9624 -2.0066)
			(stroke
				(width 0.1524)
				(type default)
			)
			(layer "B.SilkS")
		)
		(fp_circle
			(center 3.429 1.524)
			(end 3.429 1.27)
			(stroke
				(width 0.1524)
				(type default)
			)
			(fill no)
			(layer "B.SilkS")
		)
		(fp_poly
			(pts
				(xy 3.962654 3.6703) (xy 3.974846 -3.6703) (xy -3.9624 -3.6703) (xy -3.9624 3.6703)
			)
			(stroke
				(width 0)
				(type default)
			)
			(fill no)
			(layer "B.CrtYd")
		)
		(pad "1" smd rect
			(at 3.57505 2.921 90)
			(size 0.3556 1.4986)
			(layers "B.Cu" "B.Mask" "B.Paste")
			(net "N21701263")
		)
		(pad "2" smd rect
			(at 2.925064 2.921 90)
			(size 0.3556 1.4986)
			(layers "B.Cu" "B.Mask" "B.Paste")
			(net "N21699606")
		)
		(pad "3" smd rect
			(at 2.275078 2.921 90)
			(size 0.3556 1.4986)
			(layers "B.Cu" "B.Mask" "B.Paste")
			(net "N21701261")
		)
		(pad "4" smd rect
			(at 1.625092 2.921 90)
			(size 0.3556 1.4986)
			(layers "B.Cu" "B.Mask" "B.Paste")
			(net "Net_47")
		)
		(pad "5" smd rect
			(at 0.975106 2.921 90)
			(size 0.3556 1.4986)
			(layers "B.Cu" "B.Mask" "B.Paste")
			(net "Net_46")
		)
		(pad "6" smd rect
			(at 0.32512 2.921 90)
			(size 0.3556 1.4986)
			(layers "B.Cu" "B.Mask" "B.Paste")
			(net "Net_45")
		)
		(pad "7" smd rect
			(at -0.32512 2.921 90)
			(size 0.3556 1.4986)
			(layers "B.Cu" "B.Mask" "B.Paste")
			(net "Net_44")
		)
		(pad "8" smd rect
			(at -0.975106 2.921 90)
			(size 0.3556 1.4986)
			(layers "B.Cu" "B.Mask" "B.Paste")
			(net "Net_43")
		)
		(pad "9" smd rect
			(at -1.625092 2.921 90)
			(size 0.3556 1.4986)
			(layers "B.Cu" "B.Mask" "B.Paste")
			(net "Net_42")
		)
		(pad "10" smd rect
			(at -2.275078 2.921 90)
			(size 0.3556 1.4986)
			(layers "B.Cu" "B.Mask" "B.Paste")
			(net "ATTENTION_LED_N")
		)
		(pad "11" smd rect
			(at -2.925064 2.921 90)
			(size 0.3556 1.4986)
			(layers "B.Cu" "B.Mask" "B.Paste")
			(net "CM_STATUS_LED_N")
		)
		(pad "12" smd rect
			(at -3.57505 2.921 90)
			(size 0.3556 1.4986)
			(layers "B.Cu" "B.Mask" "B.Paste")
			(net "GND")
		)
		(pad "13" smd rect
			(at -3.57505 -2.921 90)
			(size 0.3556 1.4986)
			(layers "B.Cu" "B.Mask" "B.Paste")
			(net "TACKOVER_EN_N")
		)
		(pad "14" smd rect
			(at -2.925064 -2.921 90)
			(size 0.3556 1.4986)
			(layers "B.Cu" "B.Mask" "B.Paste")
			(net "PCA_CPLD_WDT2")
		)
		(pad "15" smd rect
			(at -2.275078 -2.921 90)
			(size 0.3556 1.4986)
			(layers "B.Cu" "B.Mask" "B.Paste")
			(net "POWER_SW1_PWR_CTR_N")
		)
		(pad "16" smd rect
			(at -1.625092 -2.921 90)
			(size 0.3556 1.4986)
			(layers "B.Cu" "B.Mask" "B.Paste")
			(net "POWER_SW2_PWR_CTR_N")
		)
		(pad "17" smd rect
			(at -0.975106 -2.921 90)
			(size 0.3556 1.4986)
			(layers "B.Cu" "B.Mask" "B.Paste")
			(net "POWER_SW3_PWR_CTR_N")
		)
		(pad "18" smd rect
			(at -0.32512 -2.921 90)
			(size 0.3556 1.4986)
			(layers "B.Cu" "B.Mask" "B.Paste")
			(net "Net_320")
		)
		(pad "19" smd rect
			(at 0.32512 -2.921 90)
			(size 0.3556 1.4986)
			(layers "B.Cu" "B.Mask" "B.Paste")
			(net "Net_321")
		)
		(pad "20" smd rect
			(at 0.975106 -2.921 90)
			(size 0.3556 1.4986)
			(layers "B.Cu" "B.Mask" "B.Paste")
			(net "Net_2257")
		)
		(pad "21" smd rect
			(at 1.625092 -2.921 90)
			(size 0.3556 1.4986)
			(layers "B.Cu" "B.Mask" "B.Paste")
			(net "N21698979")
		)
		(pad "22" smd rect
			(at 2.275078 -2.921 90)
			(size 0.3556 1.4986)
			(layers "B.Cu" "B.Mask" "B.Paste")
			(net "I2C_COM3_SCL")
		)
		(pad "23" smd rect
			(at 2.925064 -2.921 90)
			(size 0.3556 1.4986)
			(layers "B.Cu" "B.Mask" "B.Paste")
			(net "I2C_COM3_SDA")
		)
		(pad "24" smd rect
			(at 3.57505 -2.921 90)
			(size 0.3556 1.4986)
			(layers "B.Cu" "B.Mask" "B.Paste")
			(net "P3V3_NODE1")
		)
	)
	(footprint ""
		(layer "B.Cu")
		(at 40.685974 -162.317176 90)
		(property "Reference" "TP2"
			(at 0 0 90)
			(layer "B.SilkS")
			(hide yes)
			(effects
				(font
					(size 1.27 1.27)
				)
				(justify mirror)
			)
		)
		(property "Value" ""
			(at 0 0 90)
			(layer "B.Fab")
			(effects
				(font
					(size 1.27 1.27)
				)
				(justify mirror)
			)
		)
		(duplicate_pad_numbers_are_jumpers no)
		(fp_poly
			(pts
				(arc
					(start 0 -0.381)
					(mid 0 0.381)
					(end 0 -0.381)
				)
			)
			(stroke
				(width 0)
				(type default)
			)
			(fill no)
			(layer "B.CrtYd")
		)
		(pad "1" smd circle
			(at 0 0 270)
			(size 0.762 0.762)
			(layers "B.Cu" "B.Mask" "B.Paste")
			(net "N21311592")
		)
	)
)
